FILE_TYPE = CONNECTIVITY;
{Allegro Design Entry HDL 17.2-2016 S081 (4005846) 1/11/2022}
"PAGE_NUMBER" = 174;
0"NC";
1"P3V3_AUX\g";
2"PVNN_TERM_CPU0\g";
3"P1V05_PCH_AUX\g";
4"P3V3_AUX\g";
5"P3V3_AUX\g";
6"P3V3_AUX\g";
7"P3V3_RTC_AUX\g";
8"GND\g";
9"GND\g";
10"GND\g";
11"GND\g";
12"FM_PCH_SLP_SUS_N"CDS_PHYS_NET_NAME"FM_PCH_SLP_S4_N";
13"FM_SLP_SUS_RSM_RST_N"CDS_PHYS_NET_NAME"FM_PCH_SLP_S4_N";
14"RST_PCH_RSTBTN_R_N"CDS_PHYS_NET_NAME"FM_SLPS3_GF_N";
15"FM_BMC_RSTBTN_OUT_N"CDS_PHYS_NET_NAME"FM_PCH_SLP_S3_N";
16"FM_PCIE_EV_BIF_EN"CDS_PHYS_NET_NAME"FM_PCH_SLP_S4_N";
17"FM_PCH_TRIGGER0_R_N"CDS_PHYS_NET_NAME"FM_PCH_SLP_S4_N";
18"FM_PCH_TRIGGER1_R_N"CDS_PHYS_NET_NAME"FM_PCH_SLP_S4_N";
19"FM_PCH_TRIGGER1_N"CDS_PHYS_NET_NAME"FM_PCH_SLP_S4_N";
20"FM_PCH_TRIGGER0_N"CDS_PHYS_NET_NAME"FM_PCH_SLP_S4_N";
21"FM_PCH_TRIGGER1_R_N";
22"FM_PCH_TRIGGER0_R_N";
23"TP_PLTRST_N";
24"RST_RSMRST_PCH_N";
25"PECI_PCH";
26"TP_PCH_CPU_MSMI_N";
27"H_THERMTRIP_LVC1_N";
28"PWRGD_CPUPWRGD_GTL";
29"H_CPU_ERR0_PCH_R_N";
30"H_CPU_ERR1_PCH_R_N";
31"H_CPU_ERR2_PCH_R_N";
32"FM_PCIE_EV_BIF_EN";
33"PWRGD_PCH_PWROK";
34"PWRGD_DSW_PWROK";
35"FM_INTRUDER_HDR_PCH_N";
36"JTAG_DBP_TCK_PCH";
37"JTAG_DBP_CPU_GTL_TCK";
38"NC_PCH_RSVD<3>";
39"NC_PCH_RSVD<4>";
40"NC_PCH_RSVD<5>";
41"NC_PCH_RSVD<17>";
42"FM_PCH_SPARE0";
43"PU_ACPRESENT";
44"H_DBP_PREQ_N_PCH";
45"H_DBP_PRDY_N_PCH";
46"JTAG_DBP_PMODE";
47"TP_PCH_CPU_MEMTRIP_N";
48"FM_PCH_CPU_PWR_DEBUG_N";
49"JTAG_DBP_TMS_PCH";
50"JTAG_DBP_TDO_PCH";
51"JTAG_DBP_TDI_PCH";
52"TP_SLP_LAN_N";
53"FM_PCH_SLP_SUS_N";
54"IRQ_LVC3_WAKE_N";
55"RST_PCH_RSTBTN_R_N";
56"PWRGD_SYS_PWROK";
57"TP_PCH_SLP_A_N"CDS_PHYS_NET_NAME"FM_PCH_SLP_S4_N";
58"FM_PCH_SLP_S4_N"CDS_PHYS_NET_NAME"FM_PCH_SLP_S4_N";
59"FM_PCH_SLP_S3_N"CDS_PHYS_NET_NAME"FM_PCH_SLP_S4_N";
60"FM_BMC_PWRBTN_N";
61"PU_LAN_WAKE_N";
62"FM_PCH_SKIP_RTC_CLOCK"CDS_PHYS_NET_NAME"FM_PCH_SLP_S4_N";
63"PD_SUSCLK"CDS_PHYS_NET_NAME"CLK_33K_PCH_SUSCLK_PLD";
64"TP_PCH_SLP_S5_N"CDS_PHYS_NET_NAME"FM_PCH_SLP_S4_N";
65"TP_PCH_GPP_O_11"CDS_PHYS_NET_NAME"FM_PCH_SLP_S4_N";
%"EMMITSBURG_REV0P9"
"4","(2000,2475)","0","pure_quanta","I36";
;
PART_NUMBER"AJ0QV2N0T00"
PART_TYPE"SMLF"
MATERIAL"IC"
VALUE"GFNOCPU04302300-QV2N-MM#99A1WT"
$LOCATION"U4"
CDS_LIB"pure_quanta"
CDS_LMAN_SYM_OUTLINE"-975,800,975,-800"
NEEDS_NO_SIZE"TRUE"
CDS_LOCATION"U4"
$SEC"4"
CDS_SEC"4";
"WAKE_N \B"
$PN"AH11"54;
"TRIGGER1_N \B"
$PN"K8"21;
"TRIGGER0_N \B"
$PN"H11"22;
"SYS_RESET_N \B"
$PN"AJ10"55;
"SYS_PWROK"
$PN"AL10"56;
"SUSCLK"
$PN"AR7"63;
"SLP_SUS_N \B"
$PN"AL7"53;
"SLP_S5_N \B"
$PN"AJ13"64;
"SLP_S4_N \B"
$PN"AL13"58;
"SLP_S3_N \B"
$PN"AP8"59;
"SLP_LAN_N \B"
$PN"AK8"52;
"SLP_A_N \B"
$PN"AM11"57;
"RSVD_AW23"
$PN"AW26"38;
"RSVD_AV21"
$PN"AV21"39;
"RSVD_BF39"
$PN"BF39"40;
"RSVD_BG36"
$PN"BG36"41;
"RSMRST_N \B"
$PN"BD9"24;
"PWRBTN_N \B"
$PN"AR10"60;
"PREQ_N \B"
$PN"BF37"44;
"PRDY_N \B"
$PN"BB37"45;
"PLTRST_CPU_N \B"
$PN"M8"23;
"PCH_PWROK"
$PN"BE4"33;
"ME_PECI"
$PN"J10"25;
"LAN_WAKE_N \B"
$PN"AU7"61;
"LANPHYPC"
$PN"AJ7"65;
"JTAG_TMS"
$PN"BD37"49;
"JTAG_TDO"
$PN"BE36"50;
"JTAG_TDI"
$PN"BE38"51;
"JTAG_TCK"
$PN"BF35"36;
"JTAGX"
$PN"BD35"37;
"INTRUDER_N \B"
$PN"BG8"35;
"GPP_O_7"
$PN"AU10"62;
"GPP_O_0"
$PN"AN10"42;
"DSW_PWROK"
$PN"BE8"34;
"DBG_PMODE"
$PN"BE40"46;
"CPU_THRMTRIP_N \B"
$PN"F3"27;
"CPU_PWR_DEBUG_N \B"
$PN"F5"48;
"CPU_MSMI_N \B"
$PN"F11"26;
"CPU_MEMTRIP_N \B"
$PN"E4"47;
"CPU_ERR2_N \B"
$PN"L7"31;
"CPU_ERR1_N \B"
$PN"G7"30;
"CPU_ERR0_N \B"
$PN"J7"29;
"CPU_CATERR_N \B"
$PN"F8"32;
"CPUPWRGD"
$PN"G10"28;
"ACPRESENT"
$PN"AN7"43;
%"Q_RES"
"2","(525,1500)","0","pure_quanta","I37";
;
PART_NUMBER"CS21002FB06"
MATERIAL"CHIP"
WATTAGE"1/16W"
TOLERANCE"1%"
VALUE"1K"
PACK_TYPE"0402LF"
$LOCATION"R1026"
CDS_LIB"pure_quanta"
CDS_LOCATION"R1026"
$SEC"1"
CDS_SEC"1";
"A"
$PN"1"46;
"B"
$PN"2"3;
%"Q_RES"
"2","(-100,1500)","0","pure_quanta","I38";
;
PART_NUMBER"CS07502FB04"
PACK_TYPE"0402LF"
MATERIAL"EMPTY"
WATTAGE"1/16W"
TOLERANCE"1%"
VALUE"75"
$LOCATION"R1025"
CDS_LIB"pure_quanta"
CDS_LOCATION"R1025"
$SEC"1"
CDS_SEC"1";
"A"
$PN"1"37;
"B"
$PN"2"8;
%"UNIVERSAL_POWER"
"1","(1200,1425)","0","logical_power","I39";
;
HDL_POWER"P1V05_PCH_AUX"
CDS_LIB"logical_power";
"A"3;
%"UNIVERSAL_GND"
"1","(-100,1225)","0","logical_power","I40";
;
HDL_POWER"GND"
CDS_LIB"logical_power";
"A"8;
%"Q_RES"
"2","(-250,1500)","2","pure_quanta","I41";
;
PART_NUMBER"CS11002FB07"
WATTAGE"1/16W"
MATERIAL"CHIP"
TOLERANCE"1%"
VALUE"100"
PACK_TYPE"0402LF"
$LOCATION"R1024"
CDS_LIB"pure_quanta"
CDS_LOCATION"R1024"
$SEC"1"
CDS_SEC"1";
"A"
$PN"1"36;
"B"
$PN"2"9;
%"UNIVERSAL_GND"
"1","(-250,1225)","0","logical_power","I42";
;
HDL_POWER"GND"
CDS_LIB"logical_power";
"A"9;
%"Q_RES"
"1","(-1850,2425)","0","pure_quanta","I48";
;
PART_NUMBER"CS31002FB08"
MATERIAL"CHIP"
TOLERANCE"1%"
WATTAGE"1/16W"
VALUE"10K"
PACK_TYPE"0402LF"
$LOCATION"R1198"
CDS_LIB"pure_quanta"
CDS_LOCATION"R1198"
$SEC"1"
CDS_SEC"1";
"B"
$PN"2"43;
"A"
$PN"1"4;
%"UNIVERSAL_POWER"
"1","(-2150,2525)","0","logical_power","I49";
;
HDL_POWER"P3V3_AUX"
CDS_LIB"logical_power";
"A"4;
%"UNIVERSAL_POWER"
"1","(-125,3700)","0","logical_power","I5";
;
HDL_POWER"P3V3_AUX"
CDS_LIB"logical_power";
"A"1;
%"Q_RES"
"1","(-1125,2775)","0","pure_quanta","I50";
;
PART_NUMBER"CS21002FB06"
TOLERANCE"1%"
MATERIAL"EMPTY"
VALUE"1K"
PACK_TYPE"0402LF"
WATTAGE"1/16W"
$LOCATION"R1197"
CDS_LIB"pure_quanta"
CDS_LOCATION"R1197"
$SEC"1"
CDS_SEC"1";
"B"
$PN"2"63;
"A"
$PN"1"10;
%"UNIVERSAL_GND"
"1","(-1425,2675)","0","logical_power","I51";
;
CDS_LIB"logical_power"
HDL_POWER"GND";
"A"10;
%"Q_RES"
"1","(3850,100)","0","pure_quanta","I58";
;
PART_NUMBER"CS04992FB07"
TOLERANCE"1%"
VALUE"49.9"
WATTAGE"1/16W"
PACK_TYPE"0402LF"
MATERIAL"CHIP"
$LOCATION"R1201"
CDS_LIB"pure_quanta"
CDS_LOCATION"R1201"
$SEC"1"
CDS_SEC"1";
"B"
$PN"2"18;
"A"
$PN"1"19;
%"Q_RES"
"1","(3850,350)","0","pure_quanta","I60";
;
PART_NUMBER"CS11002FB07"
WATTAGE"1/16W"
PACK_TYPE"0402LF"
TOLERANCE"1%"
VALUE"100"
MATERIAL"CHIP"
$LOCATION"R1200"
CDS_LIB"pure_quanta"
CDS_LOCATION"R1200"
$SEC"1"
CDS_SEC"1";
"B"
$PN"2"17;
"A"
$PN"1"20;
%"Q_RES"
"2","(-250,3375)","2","pure_quanta","I63";
;
PART_NUMBER"CS24752FB03"
TOLERANCE"1%"
WATTAGE"1/16W"
MATERIAL"CHIP"
VALUE"4.75K"
PACK_TYPE"0402LF"
$LOCATION"R696"
CDS_LIB"pure_quanta"
CDS_LOCATION"R696"
$SEC"1"
CDS_SEC"1";
"A"
$PN"1"1;
"B"
$PN"2"55;
%"Q_RES"
"1","(-150,375)","0","pure_quanta","I66";
;
PART_NUMBER"CS03322FB03"
WATTAGE"1/16W"
PACK_TYPE"0402LF"
MATERIAL"CHIP"
VALUE"33.2"
TOLERANCE"1%"
$LOCATION"R697"
CDS_LIB"pure_quanta"
CDS_LOCATION"R697"
$SEC"1"
CDS_SEC"1";
"B"
$PN"2"14;
"A"
$PN"1"15;
%"Q_RES"
"2","(5400,600)","0","pure_quanta","I74";
;
PART_NUMBER"CS12002FB06"
PACK_TYPE"0402LF"
WATTAGE"1/16W"
MATERIAL"EMPTY"
TOLERANCE"1%"
VALUE"200"
$LOCATION"R1486"
CDS_LIB"pure_quanta"
CDS_LOCATION"R1486"
$SEC"1"
CDS_SEC"1";
"A"
$PN"1"2;
"B"
$PN"2"18;
%"Q_RES"
"2","(5125,600)","0","pure_quanta","I75";
;
PART_NUMBER"CS12002FB06"
TOLERANCE"1%"
WATTAGE"1/16W"
MATERIAL"EMPTY"
VALUE"200"
PACK_TYPE"0402LF"
$LOCATION"R1485"
CDS_LIB"pure_quanta"
CDS_LOCATION"R1485"
$SEC"1"
CDS_SEC"1";
"A"
$PN"1"2;
"B"
$PN"2"17;
%"UNIVERSAL_POWER"
"1","(5125,850)","0","logical_power","I76";
;
HDL_POWER"PVNN_TERM_CPU0"
CDS_LIB"logical_power";
"A"2;
%"Q_RES"
"1","(-1375,2475)","0","pure_quanta","I77";
;
PART_NUMBER"CS31002FB08"
PACK_TYPE"0402LF"
WATTAGE"1/16W"
VALUE"10K"
MATERIAL"CHIP"
TOLERANCE"1%"
$LOCATION"R453"
CDS_LIB"pure_quanta"
CDS_LOCATION"R453"
$SEC"1"
CDS_SEC"1";
"B"
$PN"2"61;
"A"
$PN"1"5;
%"UNIVERSAL_POWER"
"1","(-1675,2600)","0","logical_power","I78";
;
HDL_POWER"P3V3_AUX"
CDS_LIB"logical_power";
"A"5;
%"UNIVERSAL_POWER"
"1","(4450,-150)","0","logical_power","I80";
;
HDL_POWER"P3V3_AUX"
CDS_LIB"logical_power";
"A"6;
%"Q_RES"
"1","(3850,-350)","0","pure_quanta","I82";
;
PART_NUMBER"CS22492FB05"
PACK_TYPE"0402LF"
WATTAGE"1/16W"
MATERIAL"CHIP"
VALUE"2.49K"
TOLERANCE"1%"
$LOCATION"R1675"
CDS_LIB"pure_quanta"
CDS_LOCATION"R1675"
$SEC"1"
CDS_SEC"1";
"B"
$PN"2"6;
"A"
$PN"1"16;
%"Q_RES"
"1","(3850,-600)","0","pure_quanta","I94";
;
PART_NUMBER"CS21002FB06"
WATTAGE"1/16W"
TOLERANCE"1%"
MATERIAL"EMPTY"
PACK_TYPE"0402LF"
VALUE"1K"
LOCATION"R1676"
CDS_LIB"pure_quanta"
$SEC"1"
CDS_SEC"1";
"B"
$PN"2"11;
"A"
$PN"1"16;
%"UNIVERSAL_GND"
"1","(4450,-725)","0","logical_power","I95";
;
CDS_LIB"logical_power"
HDL_POWER"GND";
"A"11;
%"Q_RES"
"2","(5025,2450)","0","pure_quanta","I96";
;
PART_NUMBER"CS51002FB05"
TOLERANCE"1%"
VALUE"1M"
MATERIAL"CHIP"
WATTAGE"1/16W"
PACK_TYPE"0402LF"
$LOCATION"R2966"
CDS_LIB"pure_quanta"
CDS_LOCATION"R2966"
$SEC"1"
CDS_SEC"1";
"A"
$PN"1"7;
"B"
$PN"2"35;
%"UNIVERSAL_POWER"
"1","(5025,2750)","0","logical_power","I97";
;
HDL_POWER"P3V3_RTC_AUX"
CDS_LIB"logical_power";
"A"7;
%"Q_RES"
"2","(-125,3375)","0","pure_quanta","I98";
;
PART_NUMBER"CS21002FB06"
MATERIAL"CHIP"
PACK_TYPE"0402LF"
VALUE"1K"
TOLERANCE"1%"
WATTAGE"1/16W"
LOCATION"R494"
CDS_LIB"pure_quanta"
$SEC"1"
CDS_SEC"1";
"A"
$PN"1"1;
"B"
$PN"2"54;
%"Q_RES"
"1","(-150,-200)","0","pure_quanta","I99";
;
PART_NUMBER"CS03322FB03"
VALUE"33.2"
MATERIAL"CHIP"
WATTAGE"1/16W"
PACK_TYPE"0402LF"
TOLERANCE"1%"
LOCATION"R1736"
CDS_LIB"pure_quanta"
$SEC"1"
CDS_SEC"1";
"B"
$PN"2"13;
"A"
$PN"1"12;
END.
